(kicad_pcb
	(version 20260206)
	(generator "pcbnew")
	(generator_version "10.0")
	(general
		(thickness 1.6)
		(legacy_teardrops no)
	)
	(paper "A4")
	(title_block
		(title "pdpb — Lightning_PDPB_BRD.brd")
		(comment 1 "Lightning (Wiwynn / Facebook NVMe JBOF) / footprints 324-330 of 1140")
	)
	(layers
		(0 "F.Cu" signal "TOP")
		(4 "In1.Cu" signal "L2GND")
		(6 "In2.Cu" signal "L3")
		(8 "In3.Cu" signal "L4VCC")
		(10 "In4.Cu" signal "L5VCC")
		(12 "In5.Cu" signal "L6")
		(14 "In6.Cu" signal "L7GND")
		(2 "B.Cu" signal "BOTTOM")
		(9 "F.Adhes" user "F.Adhesive")
		(11 "B.Adhes" user "B.Adhesive")
		(13 "F.Paste" user "Package Geometry/Pastemask Top")
		(15 "B.Paste" user "Package Geometry/Pastemask Bottom")
		(5 "F.SilkS" user "Ref Des/Silkscreen Top")
		(7 "B.SilkS" user "Ref Des/Silkscreen Bottom")
		(1 "F.Mask" user "Board Geometry/Soldermask Top")
		(3 "B.Mask" user "Board Geometry/Soldermask Bottom")
		(17 "Dwgs.User" user "User.Drawings")
		(19 "Cmts.User" user "User.Comments")
		(21 "Eco1.User" user "User.Eco1")
		(23 "Eco2.User" user "User.Eco2")
		(25 "Edge.Cuts" user "Board Geometry/Outline")
		(27 "Margin" user)
		(31 "F.CrtYd" user "Package Geometry/Place Bound Top")
		(29 "B.CrtYd" user "Package Geometry/Place Bound Bottom")
		(35 "F.Fab" user "Ref Des/Assembly Top")
		(33 "B.Fab" user "Ref Des/Assembly Bottom")
	)
	(footprint ""
		(layer "F.Cu")
		(at 228.256592 -243.834158 180)
		(property "Reference" "SR1126"
			(at 0 0 180)
			(layer "F.SilkS")
			(hide yes)
			(effects
				(font
					(size 1.27 1.27)
				)
			)
		)
		(property "Value" "4K7R2J-2-GP"
			(at 0.064008 -3.993896 180)
			(unlocked yes)
			(layer "F.Fab")
			(hide yes)
			(effects
				(font
					(size 1.016 1.016)
					(thickness 0.1524)
				)
			)
		)
		(property "Device Type" "R402H16"
			(at 0.064008 -5.517896 180)
			(unlocked yes)
			(layer "F.Fab")
			(hide yes)
			(effects
				(font
					(size 1.016 1.016)
					(thickness 0.1524)
				)
			)
		)
		(duplicate_pad_numbers_are_jumpers no)
		(fp_line
			(start 0.508 -0.9398)
			(end -0.508 -0.9398)
			(stroke
				(width 0.1524)
				(type default)
			)
			(layer "F.SilkS")
		)
		(fp_line
			(start -0.508 -0.9398)
			(end -0.508 0.9398)
			(stroke
				(width 0.1524)
				(type default)
			)
			(layer "F.SilkS")
		)
		(fp_rect
			(start -0.508 0.9398)
			(end 0.508 -0.9398)
			(stroke
				(width 0)
				(type default)
			)
			(fill no)
			(layer "F.CrtYd")
		)
		(fp_rect
			(start -0.508 0.9398)
			(end 0.508 -0.9398)
			(stroke
				(width 0)
				(type default)
			)
			(fill no)
			(layer "F.Fab")
		)
		(pad "1" smd custom
			(at 0 -0.4445 180)
			(size 0.1397 0.1397)
			(layers "F.Cu" "F.Mask" "F.Paste")
			(net "P3V3")
			(options
				(clearance outline)
				(anchor circle)
			)
			(primitives
				(gr_poly
					(pts
						(arc
							(start -0.1778 -0.2794)
							(mid -0.249642 -0.249642)
							(end -0.2794 -0.1778)
						)
						(arc
							(start -0.2794 0.1778)
							(mid -0.249642 0.249642)
							(end -0.1778 0.2794)
						)
						(arc
							(start 0.1778 0.2794)
							(mid 0.249642 0.249642)
							(end 0.2794 0.1778)
						)
						(arc
							(start 0.2794 -0.1778)
							(mid 0.249642 -0.249642)
							(end 0.1778 -0.2794)
						)
					)
					(width 0)
					(fill yes)
				)
			)
		)
		(pad "2" smd custom
			(at 0 0.4445 180)
			(size 0.1397 0.1397)
			(layers "F.Cu" "F.Mask" "F.Paste")
			(net "SSD_ACT_DR2")
			(options
				(clearance outline)
				(anchor circle)
			)
			(primitives
				(gr_poly
					(pts
						(arc
							(start -0.1778 -0.2794)
							(mid -0.249642 -0.249642)
							(end -0.2794 -0.1778)
						)
						(arc
							(start -0.2794 0.1778)
							(mid -0.249642 0.249642)
							(end -0.1778 0.2794)
						)
						(arc
							(start 0.1778 0.2794)
							(mid 0.249642 0.249642)
							(end 0.2794 0.1778)
						)
						(arc
							(start 0.2794 -0.1778)
							(mid 0.249642 -0.249642)
							(end 0.1778 -0.2794)
						)
					)
					(width 0)
					(fill yes)
				)
			)
		)
	)
	(footprint ""
		(layer "F.Cu")
		(at 209.296 -91.186 180)
		(property "Reference" "Q12"
			(at 0 0 180)
			(layer "F.SilkS")
			(hide yes)
			(effects
				(font
					(size 1.27 1.27)
				)
			)
		)
		(property "Value" "2N7002A-7-GP"
			(at 0.127 -8.9662 180)
			(unlocked yes)
			(layer "F.Fab")
			(hide yes)
			(effects
				(font
					(size 1.016 1.016)
					(thickness 0.1524)
				)
			)
		)
		(property "Device Type" "SOT23DGS2D4H48"
			(at 0.127 -10.4902 180)
			(unlocked yes)
			(layer "F.Fab")
			(hide yes)
			(effects
				(font
					(size 1.016 1.016)
					(thickness 0.1524)
				)
			)
		)
		(duplicate_pad_numbers_are_jumpers no)
		(fp_line
			(start 1.651 1.778)
			(end 1.651 -1.778)
			(stroke
				(width 0.1524)
				(type default)
			)
			(layer "F.SilkS")
		)
		(fp_line
			(start 1.651 -1.778)
			(end -1.651 -1.778)
			(stroke
				(width 0.1524)
				(type default)
			)
			(layer "F.SilkS")
		)
		(fp_line
			(start -1.651 1.778)
			(end 1.651 1.778)
			(stroke
				(width 0.1524)
				(type default)
			)
			(layer "F.SilkS")
		)
		(fp_line
			(start -1.651 -1.778)
			(end -1.651 1.778)
			(stroke
				(width 0.1524)
				(type default)
			)
			(layer "F.SilkS")
		)
		(fp_poly
			(pts
				(xy -1.778 1.8796) (xy -1.778 -1.8796) (xy 1.778 -1.8796) (xy 1.778 1.8796)
			)
			(stroke
				(width 0)
				(type default)
			)
			(fill no)
			(layer "F.CrtYd")
		)
		(fp_poly
			(pts
				(xy -1.778 1.8796) (xy -1.778 -1.8796) (xy 1.778 -1.8796) (xy 1.778 1.8796)
			)
			(stroke
				(width 0)
				(type default)
			)
			(fill no)
			(layer "F.Fab")
		)
		(pad "D" smd custom
			(at 0 -0.9525 180)
			(size 0.1905 0.1905)
			(layers "F.Cu" "F.Mask" "F.Paste")
			(net "SW_SSD4_R")
			(options
				(clearance outline)
				(anchor circle)
			)
			(primitives
				(gr_poly
					(pts
						(arc
							(start -0.1778 0.5715)
							(mid -0.321484 0.511984)
							(end -0.381 0.3683)
						)
						(arc
							(start -0.381 -0.3683)
							(mid -0.321484 -0.511984)
							(end -0.1778 -0.5715)
						)
						(arc
							(start 0.1778 -0.5715)
							(mid 0.321484 -0.511984)
							(end 0.381 -0.3683)
						)
						(arc
							(start 0.381 0.3683)
							(mid 0.321484 0.511984)
							(end 0.1778 0.5715)
						)
					)
					(width 0)
					(fill yes)
				)
			)
		)
		(pad "G" smd custom
			(at -0.98425 0.9525 180)
			(size 0.1905 0.1905)
			(layers "F.Cu" "F.Mask" "F.Paste")
			(net "SSD4_PWREN")
			(options
				(clearance outline)
				(anchor circle)
			)
			(primitives
				(gr_poly
					(pts
						(arc
							(start -0.1778 0.5715)
							(mid -0.321484 0.511984)
							(end -0.381 0.3683)
						)
						(arc
							(start -0.381 -0.3683)
							(mid -0.321484 -0.511984)
							(end -0.1778 -0.5715)
						)
						(arc
							(start 0.1778 -0.5715)
							(mid 0.321484 -0.511984)
							(end 0.381 -0.3683)
						)
						(arc
							(start 0.381 0.3683)
							(mid 0.321484 0.511984)
							(end 0.1778 0.5715)
						)
					)
					(width 0)
					(fill yes)
				)
			)
		)
		(pad "S" smd custom
			(at 0.98425 0.9525 180)
			(size 0.1905 0.1905)
			(layers "F.Cu" "F.Mask" "F.Paste")
			(net "GND")
			(options
				(clearance outline)
				(anchor circle)
			)
			(primitives
				(gr_poly
					(pts
						(arc
							(start -0.1778 0.5715)
							(mid -0.321484 0.511984)
							(end -0.381 0.3683)
						)
						(arc
							(start -0.381 -0.3683)
							(mid -0.321484 -0.511984)
							(end -0.1778 -0.5715)
						)
						(arc
							(start 0.1778 -0.5715)
							(mid 0.321484 -0.511984)
							(end 0.381 -0.3683)
						)
						(arc
							(start 0.381 0.3683)
							(mid 0.321484 0.511984)
							(end 0.1778 0.5715)
						)
					)
					(width 0)
					(fill yes)
				)
			)
		)
	)
	(footprint ""
		(layer "F.Cu")
		(at 102.743 -313.055 -90)
		(property "Reference" "R9583"
			(at 0 0 270)
			(layer "F.SilkS")
			(hide yes)
			(effects
				(font
					(size 1.27 1.27)
				)
			)
		)
		(property "Value" "0R5J-L1-GP"
			(at 0 -8.9535 270)
			(unlocked yes)
			(layer "F.Fab")
			(hide yes)
			(effects
				(font
					(size 1.27 1.016)
					(thickness 0.1524)
				)
			)
		)
		(property "Device Type" "R805H24"
			(at 0 -10.6299 270)
			(unlocked yes)
			(layer "F.Fab")
			(hide yes)
			(effects
				(font
					(size 1.27 1.016)
					(thickness 0.1524)
				)
			)
		)
		(duplicate_pad_numbers_are_jumpers no)
		(fp_line
			(start -0.889 1.7018)
			(end 0.889 1.7018)
			(stroke
				(width 0.1524)
				(type default)
			)
			(layer "F.SilkS")
		)
		(fp_line
			(start 0.889 1.7018)
			(end 0.889 -0.508)
			(stroke
				(width 0.1524)
				(type default)
			)
			(layer "F.SilkS")
		)
		(fp_line
			(start -0.889 0.0762)
			(end -0.889 1.7018)
			(stroke
				(width 0.1524)
				(type default)
			)
			(layer "F.SilkS")
		)
		(fp_line
			(start -0.889 -1.7018)
			(end -0.889 0.2794)
			(stroke
				(width 0.1524)
				(type default)
			)
			(layer "F.SilkS")
		)
		(fp_line
			(start 0.889 -1.7018)
			(end 0.889 -0.381)
			(stroke
				(width 0.1524)
				(type default)
			)
			(layer "F.SilkS")
		)
		(fp_line
			(start 0.889 -1.7018)
			(end -0.889 -1.7018)
			(stroke
				(width 0.1524)
				(type default)
			)
			(layer "F.SilkS")
		)
		(fp_poly
			(pts
				(xy 0.9652 -1.778) (xy 0.9652 1.778) (xy -0.9652 1.778) (xy -0.9652 -1.778)
			)
			(stroke
				(width 0)
				(type default)
			)
			(fill no)
			(layer "F.CrtYd")
		)
		(fp_rect
			(start -0.9652 1.778)
			(end 0.9652 -1.778)
			(stroke
				(width 0)
				(type default)
			)
			(fill no)
			(layer "F.Fab")
		)
		(pad "1" smd rect
			(at 0 -0.9652 270)
			(size 1.397 1.143)
			(layers "F.Cu" "F.Mask" "F.Paste")
			(net "P3V3")
		)
		(pad "2" smd rect
			(at 0 0.9652 270)
			(size 1.397 1.143)
			(layers "F.Cu" "F.Mask" "F.Paste")
			(net "VDD_IO_2")
		)
	)
	(footprint ""
		(layer "F.Cu")
		(at 45.212 -242.443)
		(property "Reference" "SR1136"
			(at 0 0 0)
			(layer "F.SilkS")
			(hide yes)
			(effects
				(font
					(size 1.27 1.27)
				)
			)
		)
		(property "Value" "4K7R2J-2-GP"
			(at 0.064008 -3.993896 0)
			(unlocked yes)
			(layer "F.Fab")
			(hide yes)
			(effects
				(font
					(size 1.016 1.016)
					(thickness 0.1524)
				)
			)
		)
		(property "Device Type" "R402H16"
			(at 0.064008 -5.517896 0)
			(unlocked yes)
			(layer "F.Fab")
			(hide yes)
			(effects
				(font
					(size 1.016 1.016)
					(thickness 0.1524)
				)
			)
		)
		(duplicate_pad_numbers_are_jumpers no)
		(fp_line
			(start -0.508 -0.9398)
			(end -0.508 0.9398)
			(stroke
				(width 0.1524)
				(type default)
			)
			(layer "F.SilkS")
		)
		(fp_line
			(start 0.508 -0.9398)
			(end -0.508 -0.9398)
			(stroke
				(width 0.1524)
				(type default)
			)
			(layer "F.SilkS")
		)
		(fp_rect
			(start -0.508 0.9398)
			(end 0.508 -0.9398)
			(stroke
				(width 0)
				(type default)
			)
			(fill no)
			(layer "F.CrtYd")
		)
		(fp_rect
			(start -0.508 0.9398)
			(end 0.508 -0.9398)
			(stroke
				(width 0)
				(type default)
			)
			(fill no)
			(layer "F.Fab")
		)
		(pad "1" smd custom
			(at 0 -0.4445)
			(size 0.1397 0.1397)
			(layers "F.Cu" "F.Mask" "F.Paste")
			(net "P3V3")
			(options
				(clearance outline)
				(anchor circle)
			)
			(primitives
				(gr_poly
					(pts
						(arc
							(start -0.1778 -0.2794)
							(mid -0.249642 -0.249642)
							(end -0.2794 -0.1778)
						)
						(arc
							(start -0.2794 0.1778)
							(mid -0.249642 0.249642)
							(end -0.1778 0.2794)
						)
						(arc
							(start 0.1778 0.2794)
							(mid 0.249642 0.249642)
							(end 0.2794 0.1778)
						)
						(arc
							(start 0.2794 -0.1778)
							(mid 0.249642 -0.249642)
							(end 0.1778 -0.2794)
						)
					)
					(width 0)
					(fill yes)
				)
			)
		)
		(pad "2" smd custom
			(at 0 0.4445)
			(size 0.1397 0.1397)
			(layers "F.Cu" "F.Mask" "F.Paste")
			(net "SSD_ACT_DR7")
			(options
				(clearance outline)
				(anchor circle)
			)
			(primitives
				(gr_poly
					(pts
						(arc
							(start -0.1778 -0.2794)
							(mid -0.249642 -0.249642)
							(end -0.2794 -0.1778)
						)
						(arc
							(start -0.2794 0.1778)
							(mid -0.249642 0.249642)
							(end -0.1778 0.2794)
						)
						(arc
							(start 0.1778 0.2794)
							(mid 0.249642 0.249642)
							(end 0.2794 0.1778)
						)
						(arc
							(start 0.2794 -0.1778)
							(mid 0.249642 -0.249642)
							(end 0.1778 -0.2794)
						)
					)
					(width 0)
					(fill yes)
				)
			)
		)
	)
	(footprint ""
		(layer "F.Cu")
		(at 16.26616 -259.58419 180)
		(property "Reference" "R9951"
			(at 0 0 180)
			(layer "F.SilkS")
			(hide yes)
			(effects
				(font
					(size 1.27 1.27)
				)
			)
		)
		(property "Value" "4K7R2J-2-GP"
			(at 0.064008 -3.993896 180)
			(unlocked yes)
			(layer "F.Fab")
			(hide yes)
			(effects
				(font
					(size 1.016 1.016)
					(thickness 0.1524)
				)
			)
		)
		(property "Device Type" "R402H16"
			(at 0.064008 -5.517896 180)
			(unlocked yes)
			(layer "F.Fab")
			(hide yes)
			(effects
				(font
					(size 1.016 1.016)
					(thickness 0.1524)
				)
			)
		)
		(duplicate_pad_numbers_are_jumpers no)
		(fp_line
			(start 0.508 -0.9398)
			(end -0.508 -0.9398)
			(stroke
				(width 0.1524)
				(type default)
			)
			(layer "F.SilkS")
		)
		(fp_line
			(start -0.508 -0.9398)
			(end -0.508 0.9398)
			(stroke
				(width 0.1524)
				(type default)
			)
			(layer "F.SilkS")
		)
		(fp_rect
			(start -0.508 0.9398)
			(end 0.508 -0.9398)
			(stroke
				(width 0)
				(type default)
			)
			(fill no)
			(layer "F.CrtYd")
		)
		(fp_rect
			(start -0.508 0.9398)
			(end 0.508 -0.9398)
			(stroke
				(width 0)
				(type default)
			)
			(fill no)
			(layer "F.Fab")
		)
		(pad "1" smd custom
			(at 0 -0.4445 180)
			(size 0.1397 0.1397)
			(layers "F.Cu" "F.Mask" "F.Paste")
			(net "P3V3")
			(options
				(clearance outline)
				(anchor circle)
			)
			(primitives
				(gr_poly
					(pts
						(arc
							(start -0.1778 -0.2794)
							(mid -0.249642 -0.249642)
							(end -0.2794 -0.1778)
						)
						(arc
							(start -0.2794 0.1778)
							(mid -0.249642 0.249642)
							(end -0.1778 0.2794)
						)
						(arc
							(start 0.1778 0.2794)
							(mid 0.249642 0.249642)
							(end 0.2794 0.1778)
						)
						(arc
							(start 0.2794 -0.1778)
							(mid 0.249642 -0.249642)
							(end 0.1778 -0.2794)
						)
					)
					(width 0)
					(fill yes)
				)
			)
		)
		(pad "2" smd custom
			(at 0 0.4445 180)
			(size 0.1397 0.1397)
			(layers "F.Cu" "F.Mask" "F.Paste")
			(net "ATTN_LED_DR12_MOS_N")
			(options
				(clearance outline)
				(anchor circle)
			)
			(primitives
				(gr_poly
					(pts
						(arc
							(start -0.1778 -0.2794)
							(mid -0.249642 -0.249642)
							(end -0.2794 -0.1778)
						)
						(arc
							(start -0.2794 0.1778)
							(mid -0.249642 0.249642)
							(end -0.1778 0.2794)
						)
						(arc
							(start 0.1778 0.2794)
							(mid 0.249642 0.249642)
							(end 0.2794 0.1778)
						)
						(arc
							(start 0.2794 -0.1778)
							(mid 0.249642 -0.249642)
							(end 0.1778 -0.2794)
						)
					)
					(width 0)
					(fill yes)
				)
			)
		)
	)
	(footprint ""
		(layer "F.Cu")
		(at 24.9936 -214.0966 180)
		(property "Reference" "PC1253"
			(at 0 0 180)
			(layer "F.SilkS")
			(hide yes)
			(effects
				(font
					(size 1.27 1.27)
				)
			)
		)
		(property "Value" "SCD01U50V2KX-1GP"
			(at 1.1811 -2.7051 180)
			(unlocked yes)
			(layer "F.Fab")
			(hide yes)
			(effects
				(font
					(size 1.016 1.016)
					(thickness 0.1524)
				)
			)
		)
		(property "Device Type" "C402H22"
			(at 1.1811 -4.2291 180)
			(unlocked yes)
			(layer "F.Fab")
			(hide yes)
			(effects
				(font
					(size 1.016 1.016)
					(thickness 0.1524)
				)
			)
		)
		(duplicate_pad_numbers_are_jumpers no)
		(fp_rect
			(start -0.4318 0.9525)
			(end 0.4318 -0.9525)
			(stroke
				(width 0)
				(type default)
			)
			(fill no)
			(layer "F.CrtYd")
		)
		(fp_rect
			(start -0.4318 0.9525)
			(end 0.4318 -0.9525)
			(stroke
				(width 0)
				(type default)
			)
			(fill no)
			(layer "F.Fab")
		)
		(pad "1" smd custom
			(at 0 -0.4445 180)
			(size 0.1524 0.1524)
			(layers "F.Cu" "F.Mask" "F.Paste")
			(net "P12V_SSD12")
			(options
				(clearance outline)
				(anchor circle)
			)
			(primitives
				(gr_poly
					(pts
						(arc
							(start 0.3048 -0.2032)
							(mid 0.275042 -0.275042)
							(end 0.2032 -0.3048)
						)
						(arc
							(start -0.2032 -0.3048)
							(mid -0.275042 -0.275042)
							(end -0.3048 -0.2032)
						)
						(arc
							(start -0.3048 0.2032)
							(mid -0.275042 0.275042)
							(end -0.2032 0.3048)
						)
						(arc
							(start 0.2032 0.3048)
							(mid 0.275042 0.275042)
							(end 0.3048 0.2032)
						)
					)
					(width 0)
					(fill yes)
				)
			)
		)
		(pad "2" smd custom
			(at 0 0.4445 180)
			(size 0.1524 0.1524)
			(layers "F.Cu" "F.Mask" "F.Paste")
			(net "GND")
			(options
				(clearance outline)
				(anchor circle)
			)
			(primitives
				(gr_poly
					(pts
						(arc
							(start 0.3048 -0.2032)
							(mid 0.275042 -0.275042)
							(end 0.2032 -0.3048)
						)
						(arc
							(start -0.2032 -0.3048)
							(mid -0.275042 -0.275042)
							(end -0.3048 -0.2032)
						)
						(arc
							(start -0.3048 0.2032)
							(mid -0.275042 0.275042)
							(end -0.2032 0.3048)
						)
						(arc
							(start 0.2032 0.3048)
							(mid 0.275042 0.275042)
							(end 0.3048 0.2032)
						)
					)
					(width 0)
					(fill yes)
				)
			)
		)
	)
	(footprint ""
		(layer "F.Cu")
		(at 212.217 -432.816)
		(property "Reference" "PC1286"
			(at 0 0 0)
			(layer "F.SilkS")
			(hide yes)
			(effects
				(font
					(size 1.27 1.27)
				)
			)
		)
		(property "Value" "SC22U6D3V5MX-5-GP"
			(at -0.0762 -6.1214 0)
			(unlocked yes)
			(layer "F.Fab")
			(hide yes)
			(effects
				(font
					(size 1.016 1.016)
					(thickness 0.1524)
				)
			)
		)
		(property "Device Type" "C805H56"
			(at -0.0762 -8.1534 0)
			(unlocked yes)
			(layer "F.Fab")
			(hide yes)
			(effects
				(font
					(size 1.016 1.016)
					(thickness 0.1524)
				)
			)
		)
		(duplicate_pad_numbers_are_jumpers no)
		(fp_line
			(start 0.635 0)
			(end -0.635 0)
			(stroke
				(width 0.508)
				(type default)
			)
			(layer "F.SilkS")
		)
		(fp_rect
			(start -0.9652 1.778)
			(end 0.9652 -1.778)
			(stroke
				(width 0)
				(type default)
			)
			(fill no)
			(layer "F.CrtYd")
		)
		(fp_poly
			(pts
				(xy -0.9652 -1.778) (xy 0.9652 -1.778) (xy 0.9652 1.778) (xy -0.9652 1.778)
			)
			(stroke
				(width 0)
				(type default)
			)
			(fill no)
			(layer "F.Fab")
		)
		(pad "1" smd rect
			(at 0 -0.9652)
			(size 1.397 1.143)
			(layers "F.Cu" "F.Mask" "F.Paste")
			(net "P3V3_OUT")
		)
		(pad "2" smd rect
			(at 0 0.9652)
			(size 1.397 1.143)
			(layers "F.Cu" "F.Mask" "F.Paste")
			(net "GND")
		)
	)
)
